(kicad_pcb
	(version 20260206)
	(generator "pcbnew")
	(generator_version "10.0")
	(general
		(thickness 1.6)
		(legacy_teardrops no)
	)
	(paper "A4")
	(title_block
		(title "03242023_DA0F0TMBIJ0_F0T_Motherboard_J_brd_V01_OCP.brd")
		(comment 1 "Grand Teton / footprints 3884-3890 of 6105")
	)
	(layers
		(0 "F.Cu" signal "TOP")
		(4 "In1.Cu" signal "GND")
		(6 "In2.Cu" signal "IN1")
		(8 "In3.Cu" signal "GND1")
		(10 "In4.Cu" signal "IN2")
		(12 "In5.Cu" signal "GND2")
		(14 "In6.Cu" signal "IN3")
		(16 "In7.Cu" signal "GND3")
		(18 "In8.Cu" signal "VCC")
		(20 "In9.Cu" signal "VCC1")
		(22 "In10.Cu" signal "GND4")
		(24 "In11.Cu" signal "IN4")
		(26 "In12.Cu" signal "GND5")
		(28 "In13.Cu" signal "IN5")
		(30 "In14.Cu" signal "GND6")
		(32 "In15.Cu" signal "IN6")
		(34 "In16.Cu" signal "GND7")
		(2 "B.Cu" signal "BOTTOM")
		(9 "F.Adhes" user "F.Adhesive")
		(11 "B.Adhes" user "B.Adhesive")
		(13 "F.Paste" user "Package Geometry/Pastemask Top")
		(15 "B.Paste" user "Package Geometry/Pastemask Bottom")
		(5 "F.SilkS" user "Ref Des/Silkscreen Top")
		(7 "B.SilkS" user "Ref Des/Silkscreen Bottom")
		(1 "F.Mask" user "Board Geometry/Soldermask Top")
		(3 "B.Mask" user "Board Geometry/Soldermask Bottom")
		(17 "Dwgs.User" user "User.Drawings")
		(19 "Cmts.User" user "User.Comments")
		(21 "Eco1.User" user "User.Eco1")
		(23 "Eco2.User" user "User.Eco2")
		(25 "Edge.Cuts" user "Board Geometry/Outline")
		(27 "Margin" user)
		(31 "F.CrtYd" user "Package Geometry/Place Bound Top")
		(29 "B.CrtYd" user "Package Geometry/Place Bound Bottom")
		(35 "F.Fab" user "Ref Des/Assembly Top")
		(33 "B.Fab" user "Ref Des/Assembly Bottom")
	)
	(footprint ""
		(layer "F.Cu")
		(at 36.84143 -174.804578)
		(property "Reference" "PC1284"
			(at 0 0 0)
			(layer "F.SilkS")
			(hide yes)
			(effects
				(font
					(size 1.27 1.27)
				)
			)
		)
		(property "Value" ""
			(at 0 0 0)
			(layer "F.Fab")
			(effects
				(font
					(size 1.27 1.27)
				)
			)
		)
		(duplicate_pad_numbers_are_jumpers no)
		(fp_line
			(start -0.7874 -0.4064)
			(end 0.7874 -0.4064)
			(stroke
				(width 0.1524)
				(type default)
			)
			(layer "F.SilkS")
		)
		(fp_line
			(start -0.7874 0.4064)
			(end -0.7874 -0.4064)
			(stroke
				(width 0.1524)
				(type default)
			)
			(layer "F.SilkS")
		)
		(fp_line
			(start 0.7874 -0.4064)
			(end 0.7874 0.4064)
			(stroke
				(width 0.1524)
				(type default)
			)
			(layer "F.SilkS")
		)
		(fp_line
			(start 0.7874 0.4064)
			(end -0.7874 0.4064)
			(stroke
				(width 0.1524)
				(type default)
			)
			(layer "F.SilkS")
		)
		(fp_line
			(start -0.67945 -0.305054)
			(end -0.12065 -0.305054)
			(stroke
				(width 0.1)
				(type default)
			)
			(layer "F.Fab")
		)
		(fp_line
			(start -0.67945 0.3048)
			(end -0.67945 -0.305054)
			(stroke
				(width 0.1)
				(type default)
			)
			(layer "F.Fab")
		)
		(fp_line
			(start -0.12065 -0.305054)
			(end -0.12065 -0.2794)
			(stroke
				(width 0.1)
				(type default)
			)
			(layer "F.Fab")
		)
		(fp_line
			(start -0.12065 -0.2794)
			(end 0.12065 -0.2794)
			(stroke
				(width 0.1)
				(type default)
			)
			(layer "F.Fab")
		)
		(fp_line
			(start -0.12065 0.2794)
			(end -0.12065 0.3048)
			(stroke
				(width 0.1)
				(type default)
			)
			(layer "F.Fab")
		)
		(fp_line
			(start -0.12065 0.3048)
			(end -0.67945 0.3048)
			(stroke
				(width 0.1)
				(type default)
			)
			(layer "F.Fab")
		)
		(fp_line
			(start 0.120396 0.2794)
			(end -0.12065 0.2794)
			(stroke
				(width 0.1)
				(type default)
			)
			(layer "F.Fab")
		)
		(fp_line
			(start 0.120396 0.3048)
			(end 0.120396 0.2794)
			(stroke
				(width 0.1)
				(type default)
			)
			(layer "F.Fab")
		)
		(fp_line
			(start 0.12065 -0.3048)
			(end 0.67945 -0.3048)
			(stroke
				(width 0.1)
				(type default)
			)
			(layer "F.Fab")
		)
		(fp_line
			(start 0.12065 -0.2794)
			(end 0.12065 -0.3048)
			(stroke
				(width 0.1)
				(type default)
			)
			(layer "F.Fab")
		)
		(fp_line
			(start 0.67945 -0.3048)
			(end 0.67945 0.3048)
			(stroke
				(width 0.1)
				(type default)
			)
			(layer "F.Fab")
		)
		(fp_line
			(start 0.67945 0.3048)
			(end 0.120396 0.3048)
			(stroke
				(width 0.1)
				(type default)
			)
			(layer "F.Fab")
		)
		(pad "1" smd circle
			(at -0.40005 0)
			(size 0 0)
			(layers "F.Cu" "F.Mask" "F.Paste")
			(net "PVNN_MAIN_CPU1")
		)
		(pad "2" smd circle
			(at 0.40005 0)
			(size 0 0)
			(layers "F.Cu" "F.Mask" "F.Paste")
			(net "GND")
		)
	)
	(footprint ""
		(layer "F.Cu")
		(at 461.916526 -100.470208)
		(property "Reference" "C639"
			(at 0 0 0)
			(layer "F.SilkS")
			(hide yes)
			(effects
				(font
					(size 1.27 1.27)
				)
			)
		)
		(property "Value" ""
			(at 0 0 0)
			(layer "F.Fab")
			(effects
				(font
					(size 1.27 1.27)
				)
			)
		)
		(duplicate_pad_numbers_are_jumpers no)
		(fp_line
			(start -0.7874 -0.4064)
			(end 0.7874 -0.4064)
			(stroke
				(width 0.1524)
				(type default)
			)
			(layer "F.SilkS")
		)
		(fp_line
			(start -0.7874 0.4064)
			(end -0.7874 -0.4064)
			(stroke
				(width 0.1524)
				(type default)
			)
			(layer "F.SilkS")
		)
		(fp_line
			(start 0.7874 -0.4064)
			(end 0.7874 0.4064)
			(stroke
				(width 0.1524)
				(type default)
			)
			(layer "F.SilkS")
		)
		(fp_line
			(start 0.7874 0.4064)
			(end -0.7874 0.4064)
			(stroke
				(width 0.1524)
				(type default)
			)
			(layer "F.SilkS")
		)
		(fp_line
			(start -0.67945 -0.305054)
			(end -0.12065 -0.305054)
			(stroke
				(width 0.1)
				(type default)
			)
			(layer "F.Fab")
		)
		(fp_line
			(start -0.67945 0.3048)
			(end -0.67945 -0.305054)
			(stroke
				(width 0.1)
				(type default)
			)
			(layer "F.Fab")
		)
		(fp_line
			(start -0.12065 -0.305054)
			(end -0.12065 -0.2794)
			(stroke
				(width 0.1)
				(type default)
			)
			(layer "F.Fab")
		)
		(fp_line
			(start -0.12065 -0.2794)
			(end 0.12065 -0.2794)
			(stroke
				(width 0.1)
				(type default)
			)
			(layer "F.Fab")
		)
		(fp_line
			(start -0.12065 0.2794)
			(end -0.12065 0.3048)
			(stroke
				(width 0.1)
				(type default)
			)
			(layer "F.Fab")
		)
		(fp_line
			(start -0.12065 0.3048)
			(end -0.67945 0.3048)
			(stroke
				(width 0.1)
				(type default)
			)
			(layer "F.Fab")
		)
		(fp_line
			(start 0.120396 0.2794)
			(end -0.12065 0.2794)
			(stroke
				(width 0.1)
				(type default)
			)
			(layer "F.Fab")
		)
		(fp_line
			(start 0.120396 0.3048)
			(end 0.120396 0.2794)
			(stroke
				(width 0.1)
				(type default)
			)
			(layer "F.Fab")
		)
		(fp_line
			(start 0.12065 -0.3048)
			(end 0.67945 -0.3048)
			(stroke
				(width 0.1)
				(type default)
			)
			(layer "F.Fab")
		)
		(fp_line
			(start 0.12065 -0.2794)
			(end 0.12065 -0.3048)
			(stroke
				(width 0.1)
				(type default)
			)
			(layer "F.Fab")
		)
		(fp_line
			(start 0.67945 -0.3048)
			(end 0.67945 0.3048)
			(stroke
				(width 0.1)
				(type default)
			)
			(layer "F.Fab")
		)
		(fp_line
			(start 0.67945 0.3048)
			(end 0.120396 0.3048)
			(stroke
				(width 0.1)
				(type default)
			)
			(layer "F.Fab")
		)
		(pad "1" smd circle
			(at -0.40005 0)
			(size 0 0)
			(layers "F.Cu" "F.Mask" "F.Paste")
			(net "P3V3_AUX")
		)
		(pad "2" smd circle
			(at 0.40005 0)
			(size 0 0)
			(layers "F.Cu" "F.Mask" "F.Paste")
			(net "GND")
		)
	)
	(footprint ""
		(layer "F.Cu")
		(at 393.741148 -162.360864 -90)
		(property "Reference" "R993"
			(at 0 0 270)
			(layer "F.SilkS")
			(hide yes)
			(effects
				(font
					(size 1.27 1.27)
				)
			)
		)
		(property "Value" ""
			(at 0 0 270)
			(layer "F.Fab")
			(effects
				(font
					(size 1.27 1.27)
				)
			)
		)
		(duplicate_pad_numbers_are_jumpers no)
		(fp_line
			(start -0.7874 0.4064)
			(end -0.7874 -0.4064)
			(stroke
				(width 0.1524)
				(type default)
			)
			(layer "F.SilkS")
		)
		(fp_line
			(start 0.7874 0.4064)
			(end -0.7874 0.4064)
			(stroke
				(width 0.1524)
				(type default)
			)
			(layer "F.SilkS")
		)
		(fp_line
			(start -0.7874 -0.4064)
			(end 0.7874 -0.4064)
			(stroke
				(width 0.1524)
				(type default)
			)
			(layer "F.SilkS")
		)
		(fp_line
			(start 0.7874 -0.4064)
			(end 0.7874 0.4064)
			(stroke
				(width 0.1524)
				(type default)
			)
			(layer "F.SilkS")
		)
		(fp_line
			(start -0.67945 0.3048)
			(end -0.67945 -0.305054)
			(stroke
				(width 0.1)
				(type default)
			)
			(layer "F.Fab")
		)
		(fp_line
			(start -0.12065 0.3048)
			(end -0.67945 0.3048)
			(stroke
				(width 0.1)
				(type default)
			)
			(layer "F.Fab")
		)
		(fp_line
			(start 0.120396 0.3048)
			(end 0.120396 0.2794)
			(stroke
				(width 0.1)
				(type default)
			)
			(layer "F.Fab")
		)
		(fp_line
			(start 0.67945 0.3048)
			(end 0.120396 0.3048)
			(stroke
				(width 0.1)
				(type default)
			)
			(layer "F.Fab")
		)
		(fp_line
			(start -0.12065 0.2794)
			(end -0.12065 0.3048)
			(stroke
				(width 0.1)
				(type default)
			)
			(layer "F.Fab")
		)
		(fp_line
			(start 0.120396 0.2794)
			(end -0.12065 0.2794)
			(stroke
				(width 0.1)
				(type default)
			)
			(layer "F.Fab")
		)
		(fp_line
			(start -0.12065 -0.2794)
			(end 0.12065 -0.2794)
			(stroke
				(width 0.1)
				(type default)
			)
			(layer "F.Fab")
		)
		(fp_line
			(start 0.12065 -0.2794)
			(end 0.12065 -0.3048)
			(stroke
				(width 0.1)
				(type default)
			)
			(layer "F.Fab")
		)
		(fp_line
			(start 0.12065 -0.3048)
			(end 0.67945 -0.3048)
			(stroke
				(width 0.1)
				(type default)
			)
			(layer "F.Fab")
		)
		(fp_line
			(start 0.67945 -0.3048)
			(end 0.67945 0.3048)
			(stroke
				(width 0.1)
				(type default)
			)
			(layer "F.Fab")
		)
		(fp_line
			(start -0.67945 -0.305054)
			(end -0.12065 -0.305054)
			(stroke
				(width 0.1)
				(type default)
			)
			(layer "F.Fab")
		)
		(fp_line
			(start -0.12065 -0.305054)
			(end -0.12065 -0.2794)
			(stroke
				(width 0.1)
				(type default)
			)
			(layer "F.Fab")
		)
		(pad "1" smd circle
			(at -0.40005 0 270)
			(size 0 0)
			(layers "F.Cu" "F.Mask" "F.Paste")
			(net "SMB_S3M_CPU0_SCL")
		)
		(pad "2" smd circle
			(at 0.40005 0 270)
			(size 0 0)
			(layers "F.Cu" "F.Mask" "F.Paste")
			(net "SMB_S3M_CPU0_R_SCL")
		)
	)
	(footprint ""
		(layer "F.Cu")
		(at 201.00036 -120.614948)
		(property "Reference" "R736"
			(at 0 0 0)
			(layer "F.SilkS")
			(hide yes)
			(effects
				(font
					(size 1.27 1.27)
				)
			)
		)
		(property "Value" ""
			(at 0 0 0)
			(layer "F.Fab")
			(effects
				(font
					(size 1.27 1.27)
				)
			)
		)
		(duplicate_pad_numbers_are_jumpers no)
		(fp_line
			(start -0.7874 -0.4064)
			(end 0.7874 -0.4064)
			(stroke
				(width 0.1524)
				(type default)
			)
			(layer "F.SilkS")
		)
		(fp_line
			(start -0.7874 0.4064)
			(end -0.7874 -0.4064)
			(stroke
				(width 0.1524)
				(type default)
			)
			(layer "F.SilkS")
		)
		(fp_line
			(start 0.7874 -0.4064)
			(end 0.7874 0.4064)
			(stroke
				(width 0.1524)
				(type default)
			)
			(layer "F.SilkS")
		)
		(fp_line
			(start 0.7874 0.4064)
			(end -0.7874 0.4064)
			(stroke
				(width 0.1524)
				(type default)
			)
			(layer "F.SilkS")
		)
		(fp_line
			(start -0.67945 -0.305054)
			(end -0.12065 -0.305054)
			(stroke
				(width 0.1)
				(type default)
			)
			(layer "F.Fab")
		)
		(fp_line
			(start -0.67945 0.3048)
			(end -0.67945 -0.305054)
			(stroke
				(width 0.1)
				(type default)
			)
			(layer "F.Fab")
		)
		(fp_line
			(start -0.12065 -0.305054)
			(end -0.12065 -0.2794)
			(stroke
				(width 0.1)
				(type default)
			)
			(layer "F.Fab")
		)
		(fp_line
			(start -0.12065 -0.2794)
			(end 0.12065 -0.2794)
			(stroke
				(width 0.1)
				(type default)
			)
			(layer "F.Fab")
		)
		(fp_line
			(start -0.12065 0.2794)
			(end -0.12065 0.3048)
			(stroke
				(width 0.1)
				(type default)
			)
			(layer "F.Fab")
		)
		(fp_line
			(start -0.12065 0.3048)
			(end -0.67945 0.3048)
			(stroke
				(width 0.1)
				(type default)
			)
			(layer "F.Fab")
		)
		(fp_line
			(start 0.120396 0.2794)
			(end -0.12065 0.2794)
			(stroke
				(width 0.1)
				(type default)
			)
			(layer "F.Fab")
		)
		(fp_line
			(start 0.120396 0.3048)
			(end 0.120396 0.2794)
			(stroke
				(width 0.1)
				(type default)
			)
			(layer "F.Fab")
		)
		(fp_line
			(start 0.12065 -0.3048)
			(end 0.67945 -0.3048)
			(stroke
				(width 0.1)
				(type default)
			)
			(layer "F.Fab")
		)
		(fp_line
			(start 0.12065 -0.2794)
			(end 0.12065 -0.3048)
			(stroke
				(width 0.1)
				(type default)
			)
			(layer "F.Fab")
		)
		(fp_line
			(start 0.67945 -0.3048)
			(end 0.67945 0.3048)
			(stroke
				(width 0.1)
				(type default)
			)
			(layer "F.Fab")
		)
		(fp_line
			(start 0.67945 0.3048)
			(end 0.120396 0.3048)
			(stroke
				(width 0.1)
				(type default)
			)
			(layer "F.Fab")
		)
		(pad "1" smd circle
			(at -0.40005 0)
			(size 0 0)
			(layers "F.Cu" "F.Mask" "F.Paste")
			(net "FM_DIMM_12V_CPS_SX_N")
		)
		(pad "2" smd circle
			(at 0.40005 0)
			(size 0 0)
			(layers "F.Cu" "F.Mask" "F.Paste")
			(net "GND")
		)
	)
	(footprint ""
		(layer "F.Cu")
		(at 303.954688 -402.371052 -90)
		(property "Reference" "C1578"
			(at 0 0 270)
			(layer "F.SilkS")
			(hide yes)
			(effects
				(font
					(size 1.27 1.27)
				)
			)
		)
		(property "Value" ""
			(at 0 0 270)
			(layer "F.Fab")
			(effects
				(font
					(size 1.27 1.27)
				)
			)
		)
		(duplicate_pad_numbers_are_jumpers no)
		(fp_line
			(start -0.299974 0.150114)
			(end -0.299974 -0.150114)
			(stroke
				(width 0.1)
				(type default)
			)
			(layer "F.Fab")
		)
		(fp_line
			(start 0.299974 0.150114)
			(end -0.299974 0.150114)
			(stroke
				(width 0.1)
				(type default)
			)
			(layer "F.Fab")
		)
		(fp_line
			(start -0.299974 -0.150114)
			(end 0.299974 -0.150114)
			(stroke
				(width 0.1)
				(type default)
			)
			(layer "F.Fab")
		)
		(fp_line
			(start 0.299974 -0.150114)
			(end 0.299974 0.150114)
			(stroke
				(width 0.1)
				(type default)
			)
			(layer "F.Fab")
		)
		(pad "1" smd rect
			(at -0.2667 0 270)
			(size 0.3048 0.381)
			(layers "F.Cu" "F.Mask" "F.Paste")
			(net "P5E_CPU0_PE4_TX_C_DN<0>")
		)
		(pad "2" smd rect
			(at 0.2667 0 270)
			(size 0.3048 0.381)
			(layers "F.Cu" "F.Mask" "F.Paste")
			(net "P5E_CPU0_PE4_TX_DN<0>")
		)
	)
	(footprint ""
		(layer "F.Cu")
		(at 385.318 -34.585148)
		(property "Reference" "R4618"
			(at 0 0 0)
			(layer "F.SilkS")
			(hide yes)
			(effects
				(font
					(size 1.27 1.27)
				)
			)
		)
		(property "Value" ""
			(at 0 0 0)
			(layer "F.Fab")
			(effects
				(font
					(size 1.27 1.27)
				)
			)
		)
		(duplicate_pad_numbers_are_jumpers no)
		(fp_line
			(start -0.7874 -0.4064)
			(end 0.7874 -0.4064)
			(stroke
				(width 0.1524)
				(type default)
			)
			(layer "F.SilkS")
		)
		(fp_line
			(start -0.7874 0.4064)
			(end -0.7874 -0.4064)
			(stroke
				(width 0.1524)
				(type default)
			)
			(layer "F.SilkS")
		)
		(fp_line
			(start 0.7874 -0.4064)
			(end 0.7874 0.4064)
			(stroke
				(width 0.1524)
				(type default)
			)
			(layer "F.SilkS")
		)
		(fp_line
			(start 0.7874 0.4064)
			(end -0.7874 0.4064)
			(stroke
				(width 0.1524)
				(type default)
			)
			(layer "F.SilkS")
		)
		(fp_line
			(start -0.67945 -0.305054)
			(end -0.12065 -0.305054)
			(stroke
				(width 0.1)
				(type default)
			)
			(layer "F.Fab")
		)
		(fp_line
			(start -0.67945 0.3048)
			(end -0.67945 -0.305054)
			(stroke
				(width 0.1)
				(type default)
			)
			(layer "F.Fab")
		)
		(fp_line
			(start -0.12065 -0.305054)
			(end -0.12065 -0.2794)
			(stroke
				(width 0.1)
				(type default)
			)
			(layer "F.Fab")
		)
		(fp_line
			(start -0.12065 -0.2794)
			(end 0.12065 -0.2794)
			(stroke
				(width 0.1)
				(type default)
			)
			(layer "F.Fab")
		)
		(fp_line
			(start -0.12065 0.2794)
			(end -0.12065 0.3048)
			(stroke
				(width 0.1)
				(type default)
			)
			(layer "F.Fab")
		)
		(fp_line
			(start -0.12065 0.3048)
			(end -0.67945 0.3048)
			(stroke
				(width 0.1)
				(type default)
			)
			(layer "F.Fab")
		)
		(fp_line
			(start 0.120396 0.2794)
			(end -0.12065 0.2794)
			(stroke
				(width 0.1)
				(type default)
			)
			(layer "F.Fab")
		)
		(fp_line
			(start 0.120396 0.3048)
			(end 0.120396 0.2794)
			(stroke
				(width 0.1)
				(type default)
			)
			(layer "F.Fab")
		)
		(fp_line
			(start 0.12065 -0.3048)
			(end 0.67945 -0.3048)
			(stroke
				(width 0.1)
				(type default)
			)
			(layer "F.Fab")
		)
		(fp_line
			(start 0.12065 -0.2794)
			(end 0.12065 -0.3048)
			(stroke
				(width 0.1)
				(type default)
			)
			(layer "F.Fab")
		)
		(fp_line
			(start 0.67945 -0.3048)
			(end 0.67945 0.3048)
			(stroke
				(width 0.1)
				(type default)
			)
			(layer "F.Fab")
		)
		(fp_line
			(start 0.67945 0.3048)
			(end 0.120396 0.3048)
			(stroke
				(width 0.1)
				(type default)
			)
			(layer "F.Fab")
		)
		(pad "1" smd circle
			(at -0.40005 0)
			(size 0 0)
			(layers "F.Cu" "F.Mask" "F.Paste")
			(net "HP_LVC3_OCP_V3_1_PWRGD")
		)
		(pad "2" smd circle
			(at 0.40005 0)
			(size 0 0)
			(layers "F.Cu" "F.Mask" "F.Paste")
			(net "HP_LVC3_OCP_V3_1_PWRGD_R")
		)
	)
	(footprint ""
		(layer "F.Cu")
		(at 205.397608 -407.871422 180)
		(property "Reference" "PR1134"
			(at 0 0 180)
			(layer "F.SilkS")
			(hide yes)
			(effects
				(font
					(size 1.27 1.27)
				)
			)
		)
		(property "Value" ""
			(at 0 0 180)
			(layer "F.Fab")
			(effects
				(font
					(size 1.27 1.27)
				)
			)
		)
		(duplicate_pad_numbers_are_jumpers no)
		(fp_line
			(start 0.7874 0.4064)
			(end -0.7874 0.4064)
			(stroke
				(width 0.1524)
				(type default)
			)
			(layer "F.SilkS")
		)
		(fp_line
			(start 0.7874 -0.4064)
			(end 0.7874 0.4064)
			(stroke
				(width 0.1524)
				(type default)
			)
			(layer "F.SilkS")
		)
		(fp_line
			(start -0.7874 0.4064)
			(end -0.7874 -0.4064)
			(stroke
				(width 0.1524)
				(type default)
			)
			(layer "F.SilkS")
		)
		(fp_line
			(start -0.7874 -0.4064)
			(end 0.7874 -0.4064)
			(stroke
				(width 0.1524)
				(type default)
			)
			(layer "F.SilkS")
		)
		(fp_line
			(start 0.67945 0.3048)
			(end 0.120396 0.3048)
			(stroke
				(width 0.1)
				(type default)
			)
			(layer "F.Fab")
		)
		(fp_line
			(start 0.67945 -0.3048)
			(end 0.67945 0.3048)
			(stroke
				(width 0.1)
				(type default)
			)
			(layer "F.Fab")
		)
		(fp_line
			(start 0.12065 -0.2794)
			(end 0.12065 -0.3048)
			(stroke
				(width 0.1)
				(type default)
			)
			(layer "F.Fab")
		)
		(fp_line
			(start 0.12065 -0.3048)
			(end 0.67945 -0.3048)
			(stroke
				(width 0.1)
				(type default)
			)
			(layer "F.Fab")
		)
		(fp_line
			(start 0.120396 0.3048)
			(end 0.120396 0.2794)
			(stroke
				(width 0.1)
				(type default)
			)
			(layer "F.Fab")
		)
		(fp_line
			(start 0.120396 0.2794)
			(end -0.12065 0.2794)
			(stroke
				(width 0.1)
				(type default)
			)
			(layer "F.Fab")
		)
		(fp_line
			(start -0.12065 0.3048)
			(end -0.67945 0.3048)
			(stroke
				(width 0.1)
				(type default)
			)
			(layer "F.Fab")
		)
		(fp_line
			(start -0.12065 0.2794)
			(end -0.12065 0.3048)
			(stroke
				(width 0.1)
				(type default)
			)
			(layer "F.Fab")
		)
		(fp_line
			(start -0.12065 -0.2794)
			(end 0.12065 -0.2794)
			(stroke
				(width 0.1)
				(type default)
			)
			(layer "F.Fab")
		)
		(fp_line
			(start -0.12065 -0.305054)
			(end -0.12065 -0.2794)
			(stroke
				(width 0.1)
				(type default)
			)
			(layer "F.Fab")
		)
		(fp_line
			(start -0.67945 0.3048)
			(end -0.67945 -0.305054)
			(stroke
				(width 0.1)
				(type default)
			)
			(layer "F.Fab")
		)
		(fp_line
			(start -0.67945 -0.305054)
			(end -0.12065 -0.305054)
			(stroke
				(width 0.1)
				(type default)
			)
			(layer "F.Fab")
		)
		(pad "1" smd circle
			(at -0.40005 0 180)
			(size 0 0)
			(layers "F.Cu" "F.Mask" "F.Paste")
			(net "AGND_HSC")
		)
		(pad "2" smd circle
			(at 0.40005 0 180)
			(size 0 0)
			(layers "F.Cu" "F.Mask" "F.Paste")
			(net "HSC_MODE_1")
		)
	)
)
